FILE_TYPE = CONNECTIVITY;
{Allegro Design Entry HDL 16.6-p007 (v16-6-112F) 10/10/2012}
"PAGE_NUMBER" = 54;
0"NC";
1"M_F_DQ<63:0>";
2"M_F_MA<17:0>";
3"M_F_DQS_DP<17:0>";
4"M_F_DQS_DN<17:0>";
5"M_F_BA<1:0>";
6"M_F_CS_N<7:0>";
7"M_F_ECC<7:0>";
8"M_F_CKE<3:0>";
9"M_F_BG<1:0>";
10"M_F_ODT<3:0>";
11"M_F_CLK_DP<3:0>";
12"M_F_CLK_DN<3:0>";
13"PVDDQ_DEF\g";
14"PVTT_DEF\g";
15"GND\g";
16"GND\g";
17"PVPP_DEF\g";
18"PVPP_DEF\g";
19"GND\g";
20"P12V_NVDIMM_DEF\g";
21"GND\g";
22"M_F_DQS_DP<17>";
23"M_F_DQS_DP<9>";
24"M_F_DQS_DN<9>";
25"M_F_DQS_DP<8>";
26"M_F_DQS_DP<7>";
27"M_F_DQS_DN<7>";
28"M_F_DQS_DP<16>";
29"M_F_DQS_DN<16>";
30"M_F_DQS_DP<15>";
31"M_F_DQS_DN<15>";
32"M_F_DQS_DP<14>";
33"M_F_DQS_DN<14>";
34"M_F_DQS_DP<13>";
35"M_F_DQS_DN<13>";
36"M_F_DQS_DP<12>";
37"M_F_DQS_DN<12>";
38"M_F_DQS_DP<11>";
39"M_F_DQS_DN<11>";
40"M_F_DQS_DP<10>";
41"M_F_DQS_DN<10>";
42"M_F_DQS_DN<6>";
43"M_F_DQS_DP<5>";
44"M_F_DQS_DP<1>";
45"M_F_DQS_DP<0>";
46"M_F_DQS_DN<0>";
47"M_F_DQ<61>";
48"M_F_DQ<62>";
49"M_F_DQ<63>";
50"M_F_DQ<50>";
51"M_F_DQ<52>";
52"M_F_DQ<53>";
53"M_F_DQ<54>";
54"M_F_DQ<58>";
55"M_F_DQ<57>";
56"M_F_DQ<55>";
57"M_F_DQ<56>";
58"M_F_DQ<59>";
59"M_F_DQ<60>";
60"M_F_MA<14>";
61"M_F_MA<11>";
62"M_F_MA<10>";
63"M_F_MA<9>";
64"M_F_MA<8>";
65"M_F_MA<7>";
66"M_F_MA<6>";
67"M_F_MA<5>";
68"M_F_MA<4>";
69"M_F_MA<17>";
70"M_F_MA<12>";
71"M_F_DQ<45>";
72"M_F_DQ<36>";
73"M_F_DQ<35>";
74"M_F_DQ<30>";
75"M_F_DQ<31>";
76"M_F_DQ<33>";
77"M_F_DQ<34>";
78"M_F_DQ<37>";
79"M_F_DQ<27>";
80"M_F_DQ<20>";
81"M_F_DQ<21>";
82"M_F_DQ<22>";
83"M_F_DQ<24>";
84"M_F_DQ<10>";
85"M_F_DQ<17>";
86"M_F_DQ<15>";
87"M_F_DQ<9>";
88"M_F_DQ<11>";
89"M_F_DQ<12>";
90"M_F_DQ<13>";
91"M_F_DQ<14>";
92"M_F_DQ<16>";
93"M_F_DQ<18>";
94"M_F_DQ<19>";
95"M_F_DQ<5>";
96"M_F_DQ<4>";
97"M_F_DQ<3>";
98"M_F_DQ<2>";
99"M_F_DQ<6>";
100"M_F_DQ<7>";
101"M_F_DQ<8>";
102"M_F_C<2>";
103"M_F_ALERT_N";
104"M_F_ACT_N";
105"M_F_CLK_DN<2>";
106"M_F_CLK_DN<3>";
107"M_F_CLK_DP<3>";
108"M_F_CLK_DP<2>";
109"M_F_CKE<2>";
110"M_F_CS_N<4>";
111"M_F_ODT<3>";
112"M_F_ODT<2>";
113"M_F_ECC<7>";
114"M_F_MA<2>";
115"M_F_BA<0>";
116"M_F_BG<1>";
117"M_F_BG<0>";
118"M_F_CKE<3>";
119"M_F_ECC<0>";
120"M_F_ECC<1>";
121"M_F_ECC<2>";
122"M_F_ECC<3>";
123"M_F_ECC<4>";
124"M_F_ECC<5>";
125"M_F_ECC<6>";
126"M_F_MA<3>";
127"M_F_MA<0>";
128"M_F_CS_N<5>";
129"M_F_CS_N<6>";
130"M_F_CS_N<7>";
131"M_F_BA<1>";
132"M_DEF_RST_N";
133"M_F_PAR";
134"FM_DIMM_EVENT_COD_N";
135"FM_ADR_COMPLETE_DEF_N";
136"SMB_DDR_DEF_VPP_SDA";
137"SMB_DDR_DEF_VPP_SCL";
138"TP_CH_F_DIMM_F1_RFU_1";
139"TP_CH_F_DIMM_F1_RFU_0";
140"TP_CH_F_DIMM_F1_RFU_2";
141"M_F_VREF";
142"M_F_DQ<0>";
143"M_F_DQ<1>";
144"M_F_DQS_DN<17>";
145"M_F_DQS_DN<8>";
146"M_F_DQ<51>";
147"M_F_DQ<49>";
148"M_F_DQ<48>";
149"M_F_DQ<47>";
150"M_F_DQ<44>";
151"M_F_DQ<43>";
152"M_F_DQ<42>";
153"M_F_DQ<41>";
154"M_F_DQ<40>";
155"M_F_DQ<39>";
156"M_F_DQ<38>";
157"M_F_MA<13>";
158"M_F_MA<15>";
159"M_F_MA<16>";
160"M_F_DQS_DN<1>";
161"M_F_DQS_DN<2>";
162"M_F_DQS_DP<2>";
163"M_F_DQS_DP<4>";
164"M_F_DQS_DN<5>";
165"M_F_DQS_DN<3>";
166"M_F_DQS_DP<3>";
167"M_F_DQS_DN<4>";
168"M_F_DQS_DP<6>";
169"M_F_DQ<46>";
170"M_F_MA<1>";
171"M_F_DQ<23>";
172"M_F_DQ<25>";
173"M_F_DQ<26>";
174"M_F_DQ<28>";
175"M_F_DQ<29>";
176"M_F_DQ<32>";
%"TAP"
"6","(700,4850)","2","mstr_standard","I10";
;
HDL_TAP"TRUE"
BODY_TYPE"PLUMBING"
CDS_LIB"mstr_standard";
"B \NAC \NWC"3;
"S \NAC"
BN"14"32;
%"TAP"
"6","(-1650,2050)","2","mstr_standard","I100";
;
HDL_TAP"TRUE"
BODY_TYPE"PLUMBING"
CDS_LIB"mstr_standard";
"B \NAC \NWC"1;
"S \NAC"
BN"9"87;
%"TAP"
"6","(-1650,2100)","2","mstr_standard","I101";
;
HDL_TAP"TRUE"
BODY_TYPE"PLUMBING"
CDS_LIB"mstr_standard";
"B \NAC \NWC"1;
"S \NAC"
BN"10"84;
%"TAP"
"6","(-1650,1800)","2","mstr_standard","I102";
;
HDL_TAP"TRUE"
BODY_TYPE"PLUMBING"
CDS_LIB"mstr_standard";
"B \NAC \NWC"1;
"S \NAC"
BN"4"96;
%"TAP"
"6","(-1650,1750)","2","mstr_standard","I103";
;
HDL_TAP"TRUE"
BODY_TYPE"PLUMBING"
CDS_LIB"mstr_standard";
"B \NAC \NWC"1;
"S \NAC"
BN"3"97;
%"TAP"
"6","(-1650,1850)","2","mstr_standard","I104";
;
HDL_TAP"TRUE"
BODY_TYPE"PLUMBING"
CDS_LIB"mstr_standard";
"B \NAC \NWC"1;
"S \NAC"
BN"5"95;
%"TAP"
"6","(-1650,1900)","2","mstr_standard","I105";
;
HDL_TAP"TRUE"
BODY_TYPE"PLUMBING"
CDS_LIB"mstr_standard";
"B \NAC \NWC"1;
"S \NAC"
BN"6"99;
%"TAP"
"6","(-1650,2000)","2","mstr_standard","I106";
;
HDL_TAP"TRUE"
BODY_TYPE"PLUMBING"
CDS_LIB"mstr_standard";
"B \NAC \NWC"1;
"S \NAC"
BN"8"101;
%"TAP"
"6","(-1650,1950)","2","mstr_standard","I107";
;
HDL_TAP"TRUE"
BODY_TYPE"PLUMBING"
CDS_LIB"mstr_standard";
"B \NAC \NWC"1;
"S \NAC"
BN"7"100;
%"TAP"
"6","(-1650,1600)","2","mstr_standard","I108";
;
HDL_TAP"TRUE"
BODY_TYPE"PLUMBING"
CDS_LIB"mstr_standard";
"B \NAC \NWC"1;
"S \NAC"
BN"0"142;
%"TAP"
"6","(-1650,1700)","2","mstr_standard","I109";
;
HDL_TAP"TRUE"
BODY_TYPE"PLUMBING"
CDS_LIB"mstr_standard";
"B \NAC \NWC"1;
"S \NAC"
BN"2"98;
%"TAP"
"6","(700,4950)","2","mstr_standard","I11";
;
HDL_TAP"TRUE"
BODY_TYPE"PLUMBING"
CDS_LIB"mstr_standard";
"B \NAC \NWC"3;
"S \NAC"
BN"15"30;
%"TAP"
"6","(-1650,1650)","2","mstr_standard","I110";
;
HDL_TAP"TRUE"
BODY_TYPE"PLUMBING"
CDS_LIB"mstr_standard";
"B \NAC \NWC"1;
"S \NAC"
BN"1"143;
%"SCONN288_H44441003"
"1","(-2400,3100)","0","mstr_sconn","I111";
;
CDS_SEC"1"
MATERIAL"SCONN"
LOCATION"J6L1"
PART_NUMBER"H44441-003"
BOM_SS"NOPOP"
ROOM"DDR4_CH_F1"
CDS_LOCATION"J6L1"
SEC"1"
SEC_TYPE"PIP"
CDS_LIB"mstr_sconn"
BOM_COST"MEM"
PACK_TYPE"PIP";
"DQ<63>"
$PN"280"49;
"BA<1>"
$PN"224"131;
"CK1N"
$PN"219"106;
"CK0P"
$PN"74"108;
"S3_N_C<1>"
$PN"237"130;
"S2_N_C<0>"
$PN"93"129;
"S1_N"
$PN"89"128;
"DQ<29>"
$PN"181"175;
"DQ<28>"
$PN"36"174;
"C<2>"
$PN"235"102;
"A0"
$PN"79"127;
"A1"
$PN"72"170;
"A12"
$PN"65"70;
"A13"
$PN"232"157;
"A17"
$PN"234"69;
"A3"
$PN"71"126;
"A4"
$PN"214"68;
"A5"
$PN"213"67;
"A6"
$PN"69"66;
"A7"
$PN"211"65;
"A8"
$PN"68"64;
"A9"
$PN"66"63;
"CB<6>"
$PN"54"125;
"CB<5>"
$PN"192"124;
"CB<4>"
$PN"47"123;
"CB<3>"
$PN"201"122;
"CB<2>"
$PN"56"121;
"CB<1>"
$PN"194"120;
"CB<0>"
$PN"49"119;
"CK0N"
$PN"75"105;
"CKE<1>"
$PN"203"118;
"DQ<62>"
$PN"135"48;
"DQ<61>"
$PN"273"47;
"DQ<60>"
$PN"128"59;
"DQ<59>"
$PN"282"58;
"DQ<56>"
$PN"130"57;
"DQ<55>"
$PN"269"56;
"DQ<46>"
$PN"113"169;
"DQ<45>"
$PN"251"71;
"DQ<44>"
$PN"106"150;
"DQ<43>"
$PN"260"151;
"DQ<42>"
$PN"115"152;
"DQ<41>"
$PN"253"153;
"DQ<40>"
$PN"108"154;
"DQ<39>"
$PN"247"155;
"DQ<37>"
$PN"240"78;
"DQ<34>"
$PN"104"77;
"DQ<33>"
$PN"242"76;
"DQ<32>"
$PN"97"176;
"DQ<31>"
$PN"188"75;
"DQ<30>"
$PN"43"74;
"DQ<25>"
$PN"183"172;
"DQ<24>"
$PN"38"83;
"DQ<23>"
$PN"177"171;
"DQ<22>"
$PN"32"82;
"DQ<21>"
$PN"170"81;
"DQ<20>"
$PN"25"80;
"DQ<19>"
$PN"179"94;
"DQ<18>"
$PN"34"93;
"DQ<16>"
$PN"27"92;
"DQ<14>"
$PN"21"91;
"DQ<13>"
$PN"159"90;
"DQ<12>"
$PN"14"89;
"DQ<11>"
$PN"168"88;
"DQ<10>"
$PN"23"84;
"DQ<9>"
$PN"161"87;
"DQ<8>"
$PN"16"101;
"DQ<7>"
$PN"155"100;
"DQ<6>"
$PN"10"99;
"EVENT_N"
$PN"78"134;
"PAR"
$PN"222"133;
"RESET_N"
$PN"58"132;
"RFU<2>"
$PN"144"140;
"SCL"
$PN"141"137;
"SDA"
$PN"285"136;
"VREFCA"
$PN"146"141;
"CK1P"
$PN"218"107;
"BG<0>"
$PN"63"117;
"BG<1>"
$PN"207"116;
"BA<0>"
$PN"81"115;
"SA<0>"
$PN"139"18;
"VDDSPD"
$PN"284"18;
"SA<2>"
$PN"238"18;
"SA<1>"
$PN"140"19;
"DQ<1>"
$PN"150"143;
"DQ<0>"
$PN"5"142;
"ACT_N"
$PN"62"104;
"ALERT_N"
$PN"208"103;
"A2"
$PN"216"114;
"DQ<35>"
$PN"249"73;
"DQ<36>"
$PN"95"72;
"DQ<38>"
$PN"102"156;
"A10"
$PN"225"62;
"A11"
$PN"210"61;
"A14_WE_N"
$PN"228"60;
"A15_CAS_N"
$PN"86"158;
"A16_RAS_N"
$PN"82"159;
"CB<7>"
$PN"199"113;
"ODT<0>"
$PN"87"112;
"ODT<1>"
$PN"91"111;
"CKE<0>"
$PN"60"109;
"S0_N"
$PN"84"110;
"DQ<27>"
$PN"190"79;
"DQ<26>"
$PN"45"173;
"DQ<15>"
$PN"166"86;
"DQ<17>"
$PN"172"85;
"RFU<0>"
$PN"205"139;
"RFU<1>"
$PN"227"138;
"SAVE_N_NC"
$PN"230"135;
"DQ<57>"
$PN"275"55;
"DQ<58>"
$PN"137"54;
"DQ<54>"
$PN"124"53;
"DQ<53>"
$PN"262"52;
"DQ<52>"
$PN"117"51;
"DQ<51>"
$PN"271"146;
"DQ<50>"
$PN"126"50;
"DQ<49>"
$PN"264"147;
"DQ<48>"
$PN"119"148;
"DQ<47>"
$PN"258"149;
"DQ<2>"
$PN"12"98;
"DQ<3>"
$PN"157"97;
"DQ<4>"
$PN"3"96;
"DQ<5>"
$PN"148"95;
%"TAP"
"6","(-3150,4700)","0","mstr_standard","I112";
;
HDL_TAP"TRUE"
BODY_TYPE"PLUMBING"
CDS_LIB"mstr_standard";
"B \NAC \NWC"2;
"S \NAC"
BN"16"159;
%"TAP"
"6","(-3150,4750)","0","mstr_standard","I113";
;
HDL_TAP"TRUE"
BODY_TYPE"PLUMBING"
CDS_LIB"mstr_standard";
"B \NAC \NWC"2;
"S \NAC"
BN"17"69;
%"TAP"
"6","(-3150,4650)","0","mstr_standard","I114";
;
HDL_TAP"TRUE"
BODY_TYPE"PLUMBING"
CDS_LIB"mstr_standard";
"B \NAC \NWC"2;
"S \NAC"
BN"15"158;
%"TAP"
"6","(-3150,4600)","0","mstr_standard","I115";
;
HDL_TAP"TRUE"
BODY_TYPE"PLUMBING"
CDS_LIB"mstr_standard";
"B \NAC \NWC"2;
"S \NAC"
BN"14"60;
%"TAP"
"6","(-3150,4550)","0","mstr_standard","I116";
;
HDL_TAP"TRUE"
BODY_TYPE"PLUMBING"
CDS_LIB"mstr_standard";
"B \NAC \NWC"2;
"S \NAC"
BN"13"157;
%"TAP"
"6","(-3150,4500)","0","mstr_standard","I117";
;
HDL_TAP"TRUE"
BODY_TYPE"PLUMBING"
CDS_LIB"mstr_standard";
"B \NAC \NWC"2;
"S \NAC"
BN"12"70;
%"TAP"
"6","(-3150,4450)","0","mstr_standard","I118";
;
HDL_TAP"TRUE"
BODY_TYPE"PLUMBING"
CDS_LIB"mstr_standard";
"B \NAC \NWC"2;
"S \NAC"
BN"11"61;
%"TAP"
"6","(-3150,4400)","0","mstr_standard","I119";
;
HDL_TAP"TRUE"
BODY_TYPE"PLUMBING"
CDS_LIB"mstr_standard";
"B \NAC \NWC"2;
"S \NAC"
BN"10"62;
%"TAP"
"6","(700,5050)","2","mstr_standard","I12";
;
HDL_TAP"TRUE"
BODY_TYPE"PLUMBING"
CDS_LIB"mstr_standard";
"B \NAC \NWC"3;
"S \NAC"
BN"16"28;
%"TAP"
"6","(-3150,4350)","0","mstr_standard","I120";
;
HDL_TAP"TRUE"
BODY_TYPE"PLUMBING"
CDS_LIB"mstr_standard";
"B \NAC \NWC"2;
"S \NAC"
BN"9"63;
%"TAP"
"6","(-3150,4300)","0","mstr_standard","I121";
;
HDL_TAP"TRUE"
BODY_TYPE"PLUMBING"
CDS_LIB"mstr_standard";
"B \NAC \NWC"2;
"S \NAC"
BN"8"64;
%"TAP"
"6","(-3150,4250)","0","mstr_standard","I122";
;
HDL_TAP"TRUE"
BODY_TYPE"PLUMBING"
CDS_LIB"mstr_standard";
"B \NAC \NWC"2;
"S \NAC"
BN"7"65;
%"TAP"
"6","(-3150,4200)","0","mstr_standard","I123";
;
HDL_TAP"TRUE"
BODY_TYPE"PLUMBING"
CDS_LIB"mstr_standard";
"B \NAC \NWC"2;
"S \NAC"
BN"6"66;
%"TAP"
"6","(-3150,4150)","0","mstr_standard","I124";
;
HDL_TAP"TRUE"
BODY_TYPE"PLUMBING"
CDS_LIB"mstr_standard";
"B \NAC \NWC"2;
"S \NAC"
BN"5"67;
%"TAP"
"6","(-3150,4100)","0","mstr_standard","I125";
;
HDL_TAP"TRUE"
BODY_TYPE"PLUMBING"
CDS_LIB"mstr_standard";
"B \NAC \NWC"2;
"S \NAC"
BN"4"68;
%"TAP"
"6","(-3150,4000)","0","mstr_standard","I126";
;
HDL_TAP"TRUE"
BODY_TYPE"PLUMBING"
CDS_LIB"mstr_standard";
"B \NAC \NWC"2;
"S \NAC"
BN"2"114;
%"TAP"
"6","(-3150,4050)","0","mstr_standard","I127";
;
HDL_TAP"TRUE"
BODY_TYPE"PLUMBING"
CDS_LIB"mstr_standard";
"B \NAC \NWC"2;
"S \NAC"
BN"3"126;
%"TAP"
"6","(-3150,3950)","0","mstr_standard","I128";
;
HDL_TAP"TRUE"
BODY_TYPE"PLUMBING"
CDS_LIB"mstr_standard";
"B \NAC \NWC"2;
"S \NAC"
BN"1"170;
%"TAP"
"6","(-3150,3900)","0","mstr_standard","I129";
;
HDL_TAP"TRUE"
BODY_TYPE"PLUMBING"
CDS_LIB"mstr_standard";
"B \NAC \NWC"2;
"S \NAC"
BN"0"127;
%"TAP"
"6","(700,4550)","2","mstr_standard","I13";
;
HDL_TAP"TRUE"
BODY_TYPE"PLUMBING"
CDS_LIB"mstr_standard";
"B \NAC \NWC"3;
"S \NAC"
BN"11"38;
%"TAP"
"6","(-3150,3800)","0","mstr_standard","I130";
;
HDL_TAP"TRUE"
BODY_TYPE"PLUMBING"
CDS_LIB"mstr_standard";
"B \NAC \NWC"5;
"S \NAC"
BN"1"131;
%"TAP"
"6","(-3150,3750)","0","mstr_standard","I133";
;
HDL_TAP"TRUE"
BODY_TYPE"PLUMBING"
CDS_LIB"mstr_standard";
"B \NAC \NWC"5;
"S \NAC"
BN"0"115;
%"TAP"
"6","(-3150,3700)","0","mstr_standard","I134";
;
HDL_TAP"TRUE"
BODY_TYPE"PLUMBING"
CDS_LIB"mstr_standard";
"B \NAC \NWC"9;
"S \NAC"
BN"1"116;
%"TAP"
"6","(-3150,3650)","0","mstr_standard","I135";
;
HDL_TAP"TRUE"
BODY_TYPE"PLUMBING"
CDS_LIB"mstr_standard";
"B \NAC \NWC"9;
"S \NAC"
BN"0"117;
%"TAP"
"6","(-3150,2700)","0","mstr_standard","I138";
;
HDL_TAP"TRUE"
BODY_TYPE"PLUMBING"
CDS_LIB"mstr_standard";
"B \NAC \NWC"7;
"S \NAC"
BN"7"113;
%"TAP"
"6","(-3150,2650)","0","mstr_standard","I139";
;
HDL_TAP"TRUE"
BODY_TYPE"PLUMBING"
CDS_LIB"mstr_standard";
"B \NAC \NWC"7;
"S \NAC"
BN"6"125;
%"TAP"
"6","(700,4650)","2","mstr_standard","I14";
;
HDL_TAP"TRUE"
BODY_TYPE"PLUMBING"
CDS_LIB"mstr_standard";
"B \NAC \NWC"3;
"S \NAC"
BN"12"36;
%"TAP"
"6","(-3150,2600)","0","mstr_standard","I140";
;
HDL_TAP"TRUE"
BODY_TYPE"PLUMBING"
CDS_LIB"mstr_standard";
"B \NAC \NWC"7;
"S \NAC"
BN"5"124;
%"TAP"
"6","(-3150,2550)","0","mstr_standard","I141";
;
HDL_TAP"TRUE"
BODY_TYPE"PLUMBING"
CDS_LIB"mstr_standard";
"B \NAC \NWC"7;
"S \NAC"
BN"4"123;
%"TAP"
"6","(-3150,2500)","0","mstr_standard","I142";
;
HDL_TAP"TRUE"
BODY_TYPE"PLUMBING"
CDS_LIB"mstr_standard";
"B \NAC \NWC"7;
"S \NAC"
BN"3"122;
%"TAP"
"6","(-3150,2450)","0","mstr_standard","I143";
;
HDL_TAP"TRUE"
BODY_TYPE"PLUMBING"
CDS_LIB"mstr_standard";
"B \NAC \NWC"7;
"S \NAC"
BN"2"121;
%"TAP"
"6","(-3150,2400)","0","mstr_standard","I144";
;
HDL_TAP"TRUE"
BODY_TYPE"PLUMBING"
CDS_LIB"mstr_standard";
"B \NAC \NWC"7;
"S \NAC"
BN"1"120;
%"TAP"
"6","(-3150,2350)","0","mstr_standard","I145";
;
HDL_TAP"TRUE"
BODY_TYPE"PLUMBING"
CDS_LIB"mstr_standard";
"B \NAC \NWC"7;
"S \NAC"
BN"0"119;
%"TAP"
"6","(700,4750)","2","mstr_standard","I15";
;
HDL_TAP"TRUE"
BODY_TYPE"PLUMBING"
CDS_LIB"mstr_standard";
"B \NAC \NWC"3;
"S \NAC"
BN"13"34;
%"TAP"
"6","(-3150,3550)","0","mstr_standard","I152";
;
HDL_TAP"TRUE"
BODY_TYPE"PLUMBING"
CDS_LIB"mstr_standard";
"B \NAC \NWC"11;
"S \NAC"
BN"3"107;
%"TAP"
"6","(-3150,3450)","0","mstr_standard","I153";
;
HDL_TAP"TRUE"
BODY_TYPE"PLUMBING"
CDS_LIB"mstr_standard";
"B \NAC \NWC"11;
"S \NAC"
BN"2"108;
%"TAP"
"6","(-3350,3500)","0","mstr_standard","I154";
;
HDL_TAP"TRUE"
BODY_TYPE"PLUMBING"
CDS_LIB"mstr_standard";
"B \NAC \NWC"12;
"S \NAC"
BN"3"106;
%"TAP"
"6","(-3350,3400)","0","mstr_standard","I155";
;
HDL_TAP"TRUE"
BODY_TYPE"PLUMBING"
CDS_LIB"mstr_standard";
"B \NAC \NWC"12;
"S \NAC"
BN"2"105;
%"TAP"
"6","(-3150,3250)","0","mstr_standard","I158";
;
HDL_TAP"TRUE"
BODY_TYPE"PLUMBING"
CDS_LIB"mstr_standard";
"B \NAC \NWC"6;
"S \NAC"
BN"7"130;
%"TAP"
"6","(-3150,3200)","0","mstr_standard","I159";
;
HDL_TAP"TRUE"
BODY_TYPE"PLUMBING"
CDS_LIB"mstr_standard";
"B \NAC \NWC"6;
"S \NAC"
BN"6"129;
%"PVDDQ_DEF"
"1","(-1150,2475)","0","mstr_symbols","I16";
;
HDL_POWER"PVDDQ_DEF"
ROOM"DDR4_CH_C"
BODY_TYPE"PLUMBING"
CDS_LIB"mstr_symbols"
BOM_COST"MEM"
VOLTAGE"1.2V";
"G\NAC"13;
%"TAP"
"6","(-3150,3150)","0","mstr_standard","I160";
;
HDL_TAP"TRUE"
BODY_TYPE"PLUMBING"
CDS_LIB"mstr_standard";
"B \NAC \NWC"6;
"S \NAC"
BN"5"128;
%"TAP"
"6","(-3150,3100)","0","mstr_standard","I161";
;
HDL_TAP"TRUE"
BODY_TYPE"PLUMBING"
CDS_LIB"mstr_standard";
"B \NAC \NWC"6;
"S \NAC"
BN"4"110;
%"TAP"
"6","(-3150,3000)","0","mstr_standard","I165";
;
HDL_TAP"TRUE"
BODY_TYPE"PLUMBING"
CDS_LIB"mstr_standard";
"B \NAC \NWC"8;
"S \NAC"
BN"3"118;
%"TAP"
"6","(-3150,2950)","0","mstr_standard","I166";
;
HDL_TAP"TRUE"
BODY_TYPE"PLUMBING"
CDS_LIB"mstr_standard";
"B \NAC \NWC"8;
"S \NAC"
BN"2"109;
%"TAP"
"6","(-3150,2850)","0","mstr_standard","I167";
;
HDL_TAP"TRUE"
BODY_TYPE"PLUMBING"
CDS_LIB"mstr_standard";
"B \NAC \NWC"10;
"S \NAC"
BN"3"111;
%"TAP"
"6","(-3150,2800)","0","mstr_standard","I168";
;
HDL_TAP"TRUE"
BODY_TYPE"PLUMBING"
CDS_LIB"mstr_standard";
"B \NAC \NWC"10;
"S \NAC"
BN"2"112;
%"PVTT_DEF"
"1","(-900,2600)","0","mstr_symbols","I17";
;
HDL_POWER"PVTT_DEF"
ROOM"DDR4_CH_C"
BODY_TYPE"PLUMBING"
CDS_LIB"mstr_symbols"
BOM_COST"MEM"
VOLTAGE"0.6V";
"G\NAC"14;
%"SCONN288_H44441003"
"4","(-50,1900)","0","mstr_sconn","I170";
;
CDS_SEC"4"
MATERIAL"SCONN"
PART_NUMBER"H44441-003"
LOCATION"J6L1"
BOM_SS"NOPOP"
ROOM"DDR4_CH_F1"
CDS_LOCATION"J6L1"
SEC"4"
SEC_TYPE"PIP"
CDS_LIB"mstr_sconn"
BOM_COST"MEM"
PACK_TYPE"PIP";
"VDD<0>"
$PN"236"13;
"VDD<6>"
$PN"220"13;
"VDD<10>"
$PN"209"13;
"VDD<13>"
$PN"92"13;
"VDD<16>"
$PN"85"13;
"VDD<19>"
$PN"76"13;
"VDD<23>"
$PN"64"13;
"VDD<25>"
$PN"59"13;
"VTT<0>"
$PN"221"14;
"12V<1>"
$PN"1"20;
"12V<0>"
$PN"145"20;
"VDD<24>"
$PN"61"13;
"VDD<22>"
$PN"67"13;
"VDD<21>"
$PN"70"13;
"VDD<20>"
$PN"73"13;
"VDD<18>"
$PN"80"13;
"VDD<17>"
$PN"83"13;
"VDD<15>"
$PN"88"13;
"VDD<14>"
$PN"90"13;
"VDD<12>"
$PN"204"13;
"VDD<11>"
$PN"206"13;
"VDD<9>"
$PN"212"13;
"VDD<8>"
$PN"215"13;
"VDD<7>"
$PN"217"13;
"VDD<5>"
$PN"223"13;
"VDD<4>"
$PN"226"13;
"VDD<3>"
$PN"229"13;
"VDD<2>"
$PN"231"13;
"VDD<1>"
$PN"233"13;
"VPP<4>"
$PN"142"17;
"VPP<3>"
$PN"143"17;
"VPP<2>"
$PN"288"17;
"VPP<1>"
$PN"286"17;
"VPP<0>"
$PN"287"17;
"VTT<1>"
$PN"77"14;
%"GND"
"1","(2500,1250)","2","mstr_symbols","I171";
;
HDL_POWER"GND"
ROOM"DDR4_CH_C"
BODY_TYPE"PLUMBING"
BOM_COST"MEM"
CDS_LIB"mstr_symbols"
SIZE"1B"
VOLTAGE"0";
"A\NAC"15;
%"GND"
"1","(-4600,1150)","0","mstr_symbols","I178";
;
HDL_POWER"GND"
ROOM"DDR4_CH_C"
BODY_TYPE"PLUMBING"
SIZE"1B"
BOM_COST"MEM"
CDS_LIB"mstr_symbols"
VOLTAGE"0";
"A\NAC"16;
%"CAP_A"
"1","(-4600,1400)","2","dev_discrete","I179";
;
CDS_SEC"1"
LOCATION"C4A5"
VALUE"0.01UF"
VOLTAGE"25V"
PACK_TYPE"0402V"
MATERIAL"X7R"
TOLERANCE"10%"
PART_NUMBER"A36096-045"
SEC_TYPE"0402V"
SEC"1"
ROOM"DDR4_CH_F1"
CDS_LIB"dev_discrete"
BOM_COST"MEM"
CDS_LOCATION"C4A5";
"B"
$PN"2"16;
"A"
$PN"1"141;
%"PVPP_DEF"
"1","(-750,2900)","0","mstr_symbols","I180";
;
HDL_POWER"PVPP_DEF"
ROOM"DDR4_CH_C"
BODY_TYPE"PLUMBING"
CDS_LIB"mstr_symbols"
BOM_COST"MEM"
VOLTAGE"2.5V";
"G\NAC"17;
%"PVPP_DEF"
"1","(-5200,2100)","0","mstr_symbols","I181";
;
HDL_POWER"PVPP_DEF"
ROOM"DDR4_CH_C"
BODY_TYPE"PLUMBING"
CDS_LIB"mstr_symbols"
BOM_COST"MEM"
VOLTAGE"2.5V";
"G\NAC"18;
%"GND"
"1","(-5200,1750)","0","mstr_symbols","I186";
;
HDL_POWER"GND"
ROOM"DDR4_CH_C"
BODY_TYPE"PLUMBING"
CDS_LIB"mstr_symbols"
BOM_COST"MEM"
SIZE"1B"
VOLTAGE"0";
"A\NAC"19;
%"P12V_NVDIMM_DEF"
"1","(650,2975)","0","mstr_symbols","I187";
;
HDL_POWER"P12V_NVDIMM_DEF"
BODY_TYPE"PLUMBING"
CDS_LIB"mstr_symbols"
VOLTAGE"12.0";
"G\NAC"20;
%"TAP"
"6","(900,4500)","2","mstr_standard","I19";
;
HDL_TAP"TRUE"
BODY_TYPE"PLUMBING"
CDS_LIB"mstr_standard";
"B \NAC \NWC"4;
"S \NAC"
BN"11"39;
%"TAP"
"6","(900,4400)","2","mstr_standard","I20";
;
HDL_TAP"TRUE"
BODY_TYPE"PLUMBING"
CDS_LIB"mstr_standard";
"B \NAC \NWC"4;
"S \NAC"
BN"10"41;
%"TAP"
"6","(900,4300)","2","mstr_standard","I21";
;
HDL_TAP"TRUE"
BODY_TYPE"PLUMBING"
CDS_LIB"mstr_standard";
"B \NAC \NWC"4;
"S \NAC"
BN"9"24;
%"TAP"
"6","(900,4200)","2","mstr_standard","I22";
;
HDL_TAP"TRUE"
BODY_TYPE"PLUMBING"
CDS_LIB"mstr_standard";
"B \NAC \NWC"4;
"S \NAC"
BN"8"145;
%"TAP"
"6","(900,4100)","2","mstr_standard","I23";
;
HDL_TAP"TRUE"
BODY_TYPE"PLUMBING"
CDS_LIB"mstr_standard";
"B \NAC \NWC"4;
"S \NAC"
BN"7"27;
%"TAP"
"6","(700,4450)","2","mstr_standard","I24";
;
HDL_TAP"TRUE"
BODY_TYPE"PLUMBING"
CDS_LIB"mstr_standard";
"B \NAC \NWC"3;
"S \NAC"
BN"10"40;
%"TAP"
"6","(700,4350)","2","mstr_standard","I25";
;
HDL_TAP"TRUE"
BODY_TYPE"PLUMBING"
CDS_LIB"mstr_standard";
"B \NAC \NWC"3;
"S \NAC"
BN"9"23;
%"TAP"
"6","(700,4050)","2","mstr_standard","I26";
;
HDL_TAP"TRUE"
BODY_TYPE"PLUMBING"
CDS_LIB"mstr_standard";
"B \NAC \NWC"3;
"S \NAC"
BN"6"168;
%"TAP"
"6","(700,4150)","2","mstr_standard","I27";
;
HDL_TAP"TRUE"
BODY_TYPE"PLUMBING"
CDS_LIB"mstr_standard";
"B \NAC \NWC"3;
"S \NAC"
BN"7"26;
%"TAP"
"6","(700,4250)","2","mstr_standard","I28";
;
HDL_TAP"TRUE"
BODY_TYPE"PLUMBING"
CDS_LIB"mstr_standard";
"B \NAC \NWC"3;
"S \NAC"
BN"8"25;
%"TAP"
"6","(900,4000)","2","mstr_standard","I29";
;
HDL_TAP"TRUE"
BODY_TYPE"PLUMBING"
CDS_LIB"mstr_standard";
"B \NAC \NWC"4;
"S \NAC"
BN"6"42;
%"TAP"
"6","(900,5100)","2","mstr_standard","I3";
;
HDL_TAP"TRUE"
BODY_TYPE"PLUMBING"
CDS_LIB"mstr_standard";
"B \NAC \NWC"4;
"S \NAC"
BN"17"144;
%"TAP"
"6","(900,3900)","2","mstr_standard","I30";
;
HDL_TAP"TRUE"
BODY_TYPE"PLUMBING"
CDS_LIB"mstr_standard";
"B \NAC \NWC"4;
"S \NAC"
BN"5"164;
%"TAP"
"6","(900,3800)","2","mstr_standard","I31";
;
HDL_TAP"TRUE"
BODY_TYPE"PLUMBING"
CDS_LIB"mstr_standard";
"B \NAC \NWC"4;
"S \NAC"
BN"4"167;
%"TAP"
"6","(900,3700)","2","mstr_standard","I32";
;
HDL_TAP"TRUE"
BODY_TYPE"PLUMBING"
CDS_LIB"mstr_standard";
"B \NAC \NWC"4;
"S \NAC"
BN"3"165;
%"TAP"
"6","(900,3600)","2","mstr_standard","I33";
;
HDL_TAP"TRUE"
BODY_TYPE"PLUMBING"
CDS_LIB"mstr_standard";
"B \NAC \NWC"4;
"S \NAC"
BN"2"161;
%"TAP"
"6","(700,3950)","2","mstr_standard","I34";
;
HDL_TAP"TRUE"
BODY_TYPE"PLUMBING"
CDS_LIB"mstr_standard";
"B \NAC \NWC"3;
"S \NAC"
BN"5"43;
%"TAP"
"6","(700,3850)","2","mstr_standard","I35";
;
HDL_TAP"TRUE"
BODY_TYPE"PLUMBING"
CDS_LIB"mstr_standard";
"B \NAC \NWC"3;
"S \NAC"
BN"4"163;
%"TAP"
"6","(700,3650)","2","mstr_standard","I36";
;
HDL_TAP"TRUE"
BODY_TYPE"PLUMBING"
CDS_LIB"mstr_standard";
"B \NAC \NWC"3;
"S \NAC"
BN"2"162;
%"TAP"
"6","(700,3550)","2","mstr_standard","I37";
;
HDL_TAP"TRUE"
BODY_TYPE"PLUMBING"
CDS_LIB"mstr_standard";
"B \NAC \NWC"3;
"S \NAC"
BN"1"44;
%"TAP"
"6","(700,3750)","2","mstr_standard","I38";
;
HDL_TAP"TRUE"
BODY_TYPE"PLUMBING"
CDS_LIB"mstr_standard";
"B \NAC \NWC"3;
"S \NAC"
BN"3"166;
%"TAP"
"6","(900,3400)","2","mstr_standard","I39";
;
HDL_TAP"TRUE"
BODY_TYPE"PLUMBING"
CDS_LIB"mstr_standard";
"B \NAC \NWC"4;
"S \NAC"
BN"0"46;
%"TAP"
"6","(700,5150)","2","mstr_standard","I4";
;
HDL_TAP"TRUE"
BODY_TYPE"PLUMBING"
CDS_LIB"mstr_standard";
"B \NAC \NWC"3;
"S \NAC"
BN"17"22;
%"TAP"
"6","(900,3500)","2","mstr_standard","I40";
;
HDL_TAP"TRUE"
BODY_TYPE"PLUMBING"
CDS_LIB"mstr_standard";
"B \NAC \NWC"4;
"S \NAC"
BN"1"160;
%"TAP"
"6","(700,3450)","2","mstr_standard","I41";
;
HDL_TAP"TRUE"
BODY_TYPE"PLUMBING"
CDS_LIB"mstr_standard";
"B \NAC \NWC"3;
"S \NAC"
BN"0"45;
%"SCONN288_H44441003"
"3","(1800,2550)","0","mstr_sconn","I43";
;
CDS_SEC"3"
MATERIAL"SCONN"
PART_NUMBER"H44441-003"
LOCATION"J6L1"
BOM_SS"NOPOP"
ROOM"DDR4_CH_F1"
CDS_LOCATION"J6L1"
SEC"3"
SEC_TYPE"PIP"
CDS_LIB"mstr_sconn"
BOM_COST"MEM"
PACK_TYPE"PIP";
"VSS<46>"
$PN"147"15;
"VSS<45>"
$PN"149"15;
"VSS<87>"
$PN"15"21;
"VSS<86>"
$PN"17"21;
"VSS<85>"
$PN"20"21;
"VSS<84>"
$PN"22"21;
"VSS<83>"
$PN"24"21;
"VSS<82>"
$PN"26"21;
"VSS<81>"
$PN"28"21;
"VSS<80>"
$PN"31"21;
"VSS<79>"
$PN"33"21;
"VSS<78>"
$PN"35"21;
"VSS<77>"
$PN"37"21;
"VSS<76>"
$PN"39"21;
"VSS<75>"
$PN"42"21;
"VSS<74>"
$PN"44"21;
"VSS<73>"
$PN"46"21;
"VSS<72>"
$PN"48"21;
"VSS<71>"
$PN"50"21;
"VSS<70>"
$PN"53"21;
"VSS<69>"
$PN"55"21;
"VSS<68>"
$PN"57"21;
"VSS<67>"
$PN"94"21;
"VSS<66>"
$PN"96"21;
"VSS<65>"
$PN"98"21;
"VSS<64>"
$PN"101"21;
"VSS<63>"
$PN"103"21;
"VSS<62>"
$PN"105"21;
"VSS<61>"
$PN"107"21;
"VSS<60>"
$PN"109"21;
"VSS<59>"
$PN"112"21;
"VSS<58>"
$PN"114"21;
"VSS<57>"
$PN"116"21;
"VSS<56>"
$PN"118"21;
"VSS<55>"
$PN"120"21;
"VSS<54>"
$PN"123"21;
"VSS<53>"
$PN"125"21;
"VSS<52>"
$PN"127"21;
"VSS<51>"
$PN"129"21;
"VSS<50>"
$PN"131"21;
"VSS<49>"
$PN"134"21;
"VSS<48>"
$PN"136"21;
"VSS<47>"
$PN"138"21;
"VSS<44>"
$PN"151"15;
"VSS<43>"
$PN"154"15;
"VSS<42>"
$PN"156"15;
"VSS<41>"
$PN"158"15;
"VSS<40>"
$PN"160"15;
"VSS<39>"
$PN"162"15;
"VSS<38>"
$PN"165"15;
"VSS<37>"
$PN"167"15;
"VSS<36>"
$PN"169"15;
"VSS<35>"
$PN"171"15;
"VSS<34>"
$PN"173"15;
"VSS<33>"
$PN"176"15;
"VSS<32>"
$PN"178"15;
"VSS<31>"
$PN"180"15;
"VSS<30>"
$PN"182"15;
"VSS<29>"
$PN"184"15;
"VSS<28>"
$PN"187"15;
"VSS<27>"
$PN"189"15;
"VSS<26>"
$PN"191"15;
"VSS<25>"
$PN"193"15;
"VSS<24>"
$PN"195"15;
"VSS<23>"
$PN"198"15;
"VSS<22>"
$PN"200"15;
"VSS<21>"
$PN"202"15;
"VSS<20>"
$PN"239"15;
"VSS<19>"
$PN"241"15;
"VSS<18>"
$PN"243"15;
"VSS<17>"
$PN"246"15;
"VSS<16>"
$PN"248"15;
"VSS<15>"
$PN"250"15;
"VSS<14>"
$PN"252"15;
"VSS<13>"
$PN"254"15;
"VSS<12>"
$PN"257"15;
"VSS<11>"
$PN"259"15;
"VSS<10>"
$PN"261"15;
"VSS<9>"
$PN"263"15;
"VSS<8>"
$PN"265"15;
"VSS<7>"
$PN"268"15;
"VSS<6>"
$PN"270"15;
"VSS<5>"
$PN"272"15;
"VSS<4>"
$PN"274"15;
"VSS<3>"
$PN"276"15;
"VSS<2>"
$PN"279"15;
"VSS<1>"
$PN"281"15;
"VSS<0>"
$PN"283"15;
"VSS<88>"
$PN"13"21;
"VSS<89>"
$PN"11"21;
"VSS<90>"
$PN"9"21;
"VSS<91>"
$PN"6"21;
"VSS<92>"
$PN"4"21;
"VSS<93>"
$PN"2"21;
%"GND"
"1","(1100,1250)","2","mstr_symbols","I44";
;
HDL_POWER"GND"
ROOM"DDR4_CH_C"
BODY_TYPE"PLUMBING"
BOM_COST"MEM"
SIZE"1B"
CDS_LIB"mstr_symbols"
VOLTAGE"0";
"A\NAC"21;
%"TAP"
"6","(-1650,4650)","2","mstr_standard","I46";
;
HDL_TAP"TRUE"
BODY_TYPE"PLUMBING"
CDS_LIB"mstr_standard";
"B \NAC \NWC"1;
"S \NAC"
BN"61"47;
%"TAP"
"6","(-1650,4600)","2","mstr_standard","I47";
;
HDL_TAP"TRUE"
BODY_TYPE"PLUMBING"
CDS_LIB"mstr_standard";
"B \NAC \NWC"1;
"S \NAC"
BN"60"59;
%"TAP"
"6","(-1650,4700)","2","mstr_standard","I48";
;
HDL_TAP"TRUE"
BODY_TYPE"PLUMBING"
CDS_LIB"mstr_standard";
"B \NAC \NWC"1;
"S \NAC"
BN"62"48;
%"TAP"
"6","(-1650,4750)","2","mstr_standard","I49";
;
HDL_TAP"TRUE"
BODY_TYPE"PLUMBING"
CDS_LIB"mstr_standard";
"B \NAC \NWC"1;
"S \NAC"
BN"63"49;
%"TAP"
"6","(900,5000)","2","mstr_standard","I5";
;
HDL_TAP"TRUE"
BODY_TYPE"PLUMBING"
CDS_LIB"mstr_standard";
"B \NAC \NWC"4;
"S \NAC"
BN"16"29;
%"TAP"
"6","(-1650,4350)","2","mstr_standard","I50";
;
HDL_TAP"TRUE"
BODY_TYPE"PLUMBING"
CDS_LIB"mstr_standard";
"B \NAC \NWC"1;
"S \NAC"
BN"55"56;
%"TAP"
"6","(-1650,4400)","2","mstr_standard","I51";
;
HDL_TAP"TRUE"
BODY_TYPE"PLUMBING"
CDS_LIB"mstr_standard";
"B \NAC \NWC"1;
"S \NAC"
BN"56"57;
%"TAP"
"6","(-1650,4500)","2","mstr_standard","I52";
;
HDL_TAP"TRUE"
BODY_TYPE"PLUMBING"
CDS_LIB"mstr_standard";
"B \NAC \NWC"1;
"S \NAC"
BN"58"54;
%"TAP"
"6","(-1650,4450)","2","mstr_standard","I53";
;
HDL_TAP"TRUE"
BODY_TYPE"PLUMBING"
CDS_LIB"mstr_standard";
"B \NAC \NWC"1;
"S \NAC"
BN"57"55;
%"TAP"
"6","(-1650,4550)","2","mstr_standard","I54";
;
HDL_TAP"TRUE"
BODY_TYPE"PLUMBING"
CDS_LIB"mstr_standard";
"B \NAC \NWC"1;
"S \NAC"
BN"59"58;
%"TAP"
"6","(-1650,4100)","2","mstr_standard","I55";
;
HDL_TAP"TRUE"
BODY_TYPE"PLUMBING"
CDS_LIB"mstr_standard";
"B \NAC \NWC"1;
"S \NAC"
BN"50"50;
%"TAP"
"6","(-1650,4150)","2","mstr_standard","I56";
;
HDL_TAP"TRUE"
BODY_TYPE"PLUMBING"
CDS_LIB"mstr_standard";
"B \NAC \NWC"1;
"S \NAC"
BN"51"146;
%"TAP"
"6","(-1650,4200)","2","mstr_standard","I57";
;
HDL_TAP"TRUE"
BODY_TYPE"PLUMBING"
CDS_LIB"mstr_standard";
"B \NAC \NWC"1;
"S \NAC"
BN"52"51;
%"TAP"
"6","(-1650,4300)","2","mstr_standard","I58";
;
HDL_TAP"TRUE"
BODY_TYPE"PLUMBING"
CDS_LIB"mstr_standard";
"B \NAC \NWC"1;
"S \NAC"
BN"54"53;
%"TAP"
"6","(-1650,4250)","2","mstr_standard","I59";
;
HDL_TAP"TRUE"
BODY_TYPE"PLUMBING"
CDS_LIB"mstr_standard";
"B \NAC \NWC"1;
"S \NAC"
BN"53"52;
%"TAP"
"6","(900,4900)","2","mstr_standard","I6";
;
HDL_TAP"TRUE"
BODY_TYPE"PLUMBING"
CDS_LIB"mstr_standard";
"B \NAC \NWC"4;
"S \NAC"
BN"15"31;
%"TAP"
"6","(-1650,3800)","2","mstr_standard","I60";
;
HDL_TAP"TRUE"
BODY_TYPE"PLUMBING"
CDS_LIB"mstr_standard";
"B \NAC \NWC"1;
"S \NAC"
BN"44"150;
%"TAP"
"6","(-1650,3850)","2","mstr_standard","I61";
;
HDL_TAP"TRUE"
BODY_TYPE"PLUMBING"
CDS_LIB"mstr_standard";
"B \NAC \NWC"1;
"S \NAC"
BN"45"71;
%"TAP"
"6","(-1650,3900)","2","mstr_standard","I62";
;
HDL_TAP"TRUE"
BODY_TYPE"PLUMBING"
CDS_LIB"mstr_standard";
"B \NAC \NWC"1;
"S \NAC"
BN"46"169;
%"TAP"
"6","(-1650,4000)","2","mstr_standard","I63";
;
HDL_TAP"TRUE"
BODY_TYPE"PLUMBING"
CDS_LIB"mstr_standard";
"B \NAC \NWC"1;
"S \NAC"
BN"48"148;
%"TAP"
"6","(-1650,3950)","2","mstr_standard","I64";
;
HDL_TAP"TRUE"
BODY_TYPE"PLUMBING"
CDS_LIB"mstr_standard";
"B \NAC \NWC"1;
"S \NAC"
BN"47"149;
%"TAP"
"6","(-1650,4050)","2","mstr_standard","I65";
;
HDL_TAP"TRUE"
BODY_TYPE"PLUMBING"
CDS_LIB"mstr_standard";
"B \NAC \NWC"1;
"S \NAC"
BN"49"147;
%"SCONN288_H44441003"
"2","(0,4300)","0","mstr_sconn","I66";
;
CDS_SEC"2"
LOCATION"J6L1"
PART_NUMBER"H44441-003"
MATERIAL"SCONN"
BOM_SS"NOPOP"
ROOM"DDR4_CH_F1"
CDS_LOCATION"J6L1"
SEC"2"
SEC_TYPE"PIP"
CDS_LIB"mstr_sconn"
BOM_COST"MEM"
PACK_TYPE"PIP";
"DQS0N"
$PN"152"46;
"DQS0P"
$PN"153"45;
"DQS10N"
$PN"19"41;
"DQS10P"
$PN"18"40;
"DQS11N"
$PN"30"39;
"DQS11P"
$PN"29"38;
"DQS12N"
$PN"41"37;
"DQS12P"
$PN"40"36;
"DQS13N"
$PN"100"35;
"DQS13P"
$PN"99"34;
"DQS14N"
$PN"111"33;
"DQS14P"
$PN"110"32;
"DQS15N"
$PN"122"31;
"DQS15P"
$PN"121"30;
"DQS16N"
$PN"133"29;
"DQS16P"
$PN"132"28;
"DQS17N"
$PN"52"144;
"DQS17P"
$PN"51"22;
"DQS1N"
$PN"163"160;
"DQS1P"
$PN"164"44;
"DQS2N"
$PN"174"161;
"DQS2P"
$PN"175"162;
"DQS3N"
$PN"185"165;
"DQS3P"
$PN"186"166;
"DQS4N"
$PN"244"167;
"DQS4P"
$PN"245"163;
"DQS5N"
$PN"255"164;
"DQS5P"
$PN"256"43;
"DQS6N"
$PN"266"42;
"DQS6P"
$PN"267"168;
"DQS7N"
$PN"277"27;
"DQS7P"
$PN"278"26;
"DQS8N"
$PN"196"145;
"DQS8P"
$PN"197"25;
"DQS9N"
$PN"8"24;
"DQS9P"
$PN"7"23;
%"TAP"
"6","(-1650,3650)","2","mstr_standard","I67";
;
HDL_TAP"TRUE"
BODY_TYPE"PLUMBING"
CDS_LIB"mstr_standard";
"B \NAC \NWC"1;
"S \NAC"
BN"41"153;
%"TAP"
"6","(-1650,3550)","2","mstr_standard","I68";
;
HDL_TAP"TRUE"
BODY_TYPE"PLUMBING"
CDS_LIB"mstr_standard";
"B \NAC \NWC"1;
"S \NAC"
BN"39"155;
%"TAP"
"6","(-1650,3600)","2","mstr_standard","I69";
;
HDL_TAP"TRUE"
BODY_TYPE"PLUMBING"
CDS_LIB"mstr_standard";
"B \NAC \NWC"1;
"S \NAC"
BN"40"154;
%"TAP"
"6","(900,4800)","2","mstr_standard","I7";
;
HDL_TAP"TRUE"
BODY_TYPE"PLUMBING"
CDS_LIB"mstr_standard";
"B \NAC \NWC"4;
"S \NAC"
BN"14"33;
%"TAP"
"6","(-1650,3700)","2","mstr_standard","I70";
;
HDL_TAP"TRUE"
BODY_TYPE"PLUMBING"
CDS_LIB"mstr_standard";
"B \NAC \NWC"1;
"S \NAC"
BN"42"152;
%"TAP"
"6","(-1650,3750)","2","mstr_standard","I71";
;
HDL_TAP"TRUE"
BODY_TYPE"PLUMBING"
CDS_LIB"mstr_standard";
"B \NAC \NWC"1;
"S \NAC"
BN"43"151;
%"TAP"
"6","(-1650,3350)","2","mstr_standard","I72";
;
HDL_TAP"TRUE"
BODY_TYPE"PLUMBING"
CDS_LIB"mstr_standard";
"B \NAC \NWC"1;
"S \NAC"
BN"35"73;
%"TAP"
"6","(-1650,3300)","2","mstr_standard","I73";
;
HDL_TAP"TRUE"
BODY_TYPE"PLUMBING"
CDS_LIB"mstr_standard";
"B \NAC \NWC"1;
"S \NAC"
BN"34"77;
%"TAP"
"6","(-1650,3400)","2","mstr_standard","I74";
;
HDL_TAP"TRUE"
BODY_TYPE"PLUMBING"
CDS_LIB"mstr_standard";
"B \NAC \NWC"1;
"S \NAC"
BN"36"72;
%"TAP"
"6","(-1650,3450)","2","mstr_standard","I75";
;
HDL_TAP"TRUE"
BODY_TYPE"PLUMBING"
CDS_LIB"mstr_standard";
"B \NAC \NWC"1;
"S \NAC"
BN"37"78;
%"TAP"
"6","(-1650,3500)","2","mstr_standard","I76";
;
HDL_TAP"TRUE"
BODY_TYPE"PLUMBING"
CDS_LIB"mstr_standard";
"B \NAC \NWC"1;
"S \NAC"
BN"38"156;
%"TAP"
"6","(-1650,3100)","2","mstr_standard","I77";
;
HDL_TAP"TRUE"
BODY_TYPE"PLUMBING"
CDS_LIB"mstr_standard";
"B \NAC \NWC"1;
"S \NAC"
BN"30"74;
%"TAP"
"6","(-1650,3150)","2","mstr_standard","I78";
;
HDL_TAP"TRUE"
BODY_TYPE"PLUMBING"
CDS_LIB"mstr_standard";
"B \NAC \NWC"1;
"S \NAC"
BN"31"75;
%"TAP"
"6","(-1650,3050)","2","mstr_standard","I79";
;
HDL_TAP"TRUE"
BODY_TYPE"PLUMBING"
CDS_LIB"mstr_standard";
"B \NAC \NWC"1;
"S \NAC"
BN"29"175;
%"TAP"
"6","(900,4700)","2","mstr_standard","I8";
;
HDL_TAP"TRUE"
BODY_TYPE"PLUMBING"
CDS_LIB"mstr_standard";
"B \NAC \NWC"4;
"S \NAC"
BN"13"35;
%"TAP"
"6","(-1650,3200)","2","mstr_standard","I80";
;
HDL_TAP"TRUE"
BODY_TYPE"PLUMBING"
CDS_LIB"mstr_standard";
"B \NAC \NWC"1;
"S \NAC"
BN"32"176;
%"TAP"
"6","(-1650,3250)","2","mstr_standard","I81";
;
HDL_TAP"TRUE"
BODY_TYPE"PLUMBING"
CDS_LIB"mstr_standard";
"B \NAC \NWC"1;
"S \NAC"
BN"33"76;
%"TAP"
"6","(-1650,2850)","2","mstr_standard","I82";
;
HDL_TAP"TRUE"
BODY_TYPE"PLUMBING"
CDS_LIB"mstr_standard";
"B \NAC \NWC"1;
"S \NAC"
BN"25"172;
%"TAP"
"6","(-1650,2800)","2","mstr_standard","I83";
;
HDL_TAP"TRUE"
BODY_TYPE"PLUMBING"
CDS_LIB"mstr_standard";
"B \NAC \NWC"1;
"S \NAC"
BN"24"83;
%"TAP"
"6","(-1650,2900)","2","mstr_standard","I84";
;
HDL_TAP"TRUE"
BODY_TYPE"PLUMBING"
CDS_LIB"mstr_standard";
"B \NAC \NWC"1;
"S \NAC"
BN"26"173;
%"TAP"
"6","(-1650,3000)","2","mstr_standard","I85";
;
HDL_TAP"TRUE"
BODY_TYPE"PLUMBING"
CDS_LIB"mstr_standard";
"B \NAC \NWC"1;
"S \NAC"
BN"28"174;
%"TAP"
"6","(-1650,2950)","2","mstr_standard","I86";
;
HDL_TAP"TRUE"
BODY_TYPE"PLUMBING"
CDS_LIB"mstr_standard";
"B \NAC \NWC"1;
"S \NAC"
BN"27"79;
%"TAP"
"6","(-1650,2550)","2","mstr_standard","I87";
;
HDL_TAP"TRUE"
BODY_TYPE"PLUMBING"
CDS_LIB"mstr_standard";
"B \NAC \NWC"1;
"S \NAC"
BN"19"94;
%"TAP"
"6","(-1650,2600)","2","mstr_standard","I88";
;
HDL_TAP"TRUE"
BODY_TYPE"PLUMBING"
CDS_LIB"mstr_standard";
"B \NAC \NWC"1;
"S \NAC"
BN"20"80;
%"TAP"
"6","(-1650,2650)","2","mstr_standard","I89";
;
HDL_TAP"TRUE"
BODY_TYPE"PLUMBING"
CDS_LIB"mstr_standard";
"B \NAC \NWC"1;
"S \NAC"
BN"21"81;
%"TAP"
"6","(900,4600)","2","mstr_standard","I9";
;
HDL_TAP"TRUE"
BODY_TYPE"PLUMBING"
CDS_LIB"mstr_standard";
"B \NAC \NWC"4;
"S \NAC"
BN"12"37;
%"TAP"
"6","(-1650,2750)","2","mstr_standard","I90";
;
HDL_TAP"TRUE"
BODY_TYPE"PLUMBING"
CDS_LIB"mstr_standard";
"B \NAC \NWC"1;
"S \NAC"
BN"23"171;
%"TAP"
"6","(-1650,2700)","2","mstr_standard","I91";
;
HDL_TAP"TRUE"
BODY_TYPE"PLUMBING"
CDS_LIB"mstr_standard";
"B \NAC \NWC"1;
"S \NAC"
BN"22"82;
%"TAP"
"6","(-1650,2300)","2","mstr_standard","I92";
;
HDL_TAP"TRUE"
BODY_TYPE"PLUMBING"
CDS_LIB"mstr_standard";
"B \NAC \NWC"1;
"S \NAC"
BN"14"91;
%"TAP"
"6","(-1650,2350)","2","mstr_standard","I93";
;
HDL_TAP"TRUE"
BODY_TYPE"PLUMBING"
CDS_LIB"mstr_standard";
"B \NAC \NWC"1;
"S \NAC"
BN"15"86;
%"TAP"
"6","(-1650,2450)","2","mstr_standard","I94";
;
HDL_TAP"TRUE"
BODY_TYPE"PLUMBING"
CDS_LIB"mstr_standard";
"B \NAC \NWC"1;
"S \NAC"
BN"17"85;
%"TAP"
"6","(-1650,2400)","2","mstr_standard","I95";
;
HDL_TAP"TRUE"
BODY_TYPE"PLUMBING"
CDS_LIB"mstr_standard";
"B \NAC \NWC"1;
"S \NAC"
BN"16"92;
%"TAP"
"6","(-1650,2500)","2","mstr_standard","I96";
;
HDL_TAP"TRUE"
BODY_TYPE"PLUMBING"
CDS_LIB"mstr_standard";
"B \NAC \NWC"1;
"S \NAC"
BN"18"93;
%"TAP"
"6","(-1650,2250)","2","mstr_standard","I97";
;
HDL_TAP"TRUE"
BODY_TYPE"PLUMBING"
CDS_LIB"mstr_standard";
"B \NAC \NWC"1;
"S \NAC"
BN"13"90;
%"TAP"
"6","(-1650,2150)","2","mstr_standard","I98";
;
HDL_TAP"TRUE"
BODY_TYPE"PLUMBING"
CDS_LIB"mstr_standard";
"B \NAC \NWC"1;
"S \NAC"
BN"11"88;
%"TAP"
"6","(-1650,2200)","2","mstr_standard","I99";
;
HDL_TAP"TRUE"
BODY_TYPE"PLUMBING"
CDS_LIB"mstr_standard";
"B \NAC \NWC"1;
"S \NAC"
BN"12"89;
END.
